(kicad_pcb
	(version 20260206)
	(generator "pcbnew")
	(generator_version "10.0")
	(general
		(thickness 1.6)
		(legacy_teardrops no)
	)
	(paper "A4")
	(title_block
		(title "v2-pdb — ms_pdb_v2.brd")
		(comment 1 "Open CloudServer (Microsoft) / footprints 339-340 of 348")
	)
	(layers
		(0 "F.Cu" signal "TOP")
		(4 "In1.Cu" signal "GND")
		(6 "In2.Cu" signal "IN1")
		(8 "In3.Cu" signal "VCC")
		(10 "In4.Cu" signal "VCC1")
		(12 "In5.Cu" signal "IN2")
		(14 "In6.Cu" signal "GND1")
		(2 "B.Cu" signal "BOTTOM")
		(9 "F.Adhes" user "F.Adhesive")
		(11 "B.Adhes" user "B.Adhesive")
		(13 "F.Paste" user "Package Geometry/Pastemask Top")
		(15 "B.Paste" user "Package Geometry/Pastemask Bottom")
		(5 "F.SilkS" user "Ref Des/Silkscreen Top")
		(7 "B.SilkS" user "Ref Des/Silkscreen Bottom")
		(1 "F.Mask" user "Board Geometry/Soldermask Top")
		(3 "B.Mask" user "Board Geometry/Soldermask Bottom")
		(17 "Dwgs.User" user "User.Drawings")
		(19 "Cmts.User" user "User.Comments")
		(21 "Eco1.User" user "User.Eco1")
		(23 "Eco2.User" user "User.Eco2")
		(25 "Edge.Cuts" user "Board Geometry/Outline")
		(27 "Margin" user)
		(31 "F.CrtYd" user "Package Geometry/Place Bound Top")
		(29 "B.CrtYd" user "Package Geometry/Place Bound Bottom")
		(35 "F.Fab" user "Ref Des/Assembly Top")
		(33 "B.Fab" user "Ref Des/Assembly Bottom")
	)
	(footprint ""
		(layer "B.Cu")
		(at 98.156268 -349.954596 180)
		(property "Reference" "C95"
			(at -1.279906 1.42621 0)
			(unlocked yes)
			(layer "B.SilkS")
			(effects
				(font
					(size 0.7874 0.5842)
					(thickness 0.1524)
				)
				(justify left mirror)
			)
		)
		(property "Value" ""
			(at 0 0 0)
			(layer "B.Fab")
			(effects
				(font
					(size 1.27 1.27)
				)
				(justify mirror)
			)
		)
		(duplicate_pad_numbers_are_jumpers no)
		(fp_line
			(start 0.7874 0.4064)
			(end 0.7874 -0.4064)
			(stroke
				(width 0.1524)
				(type default)
			)
			(layer "B.SilkS")
		)
		(fp_line
			(start 0.7874 -0.4064)
			(end -0.7874 -0.4064)
			(stroke
				(width 0.1524)
				(type default)
			)
			(layer "B.SilkS")
		)
		(fp_line
			(start 0 0.381)
			(end 0 -0.381)
			(stroke
				(width 0.1524)
				(type default)
			)
			(layer "B.SilkS")
		)
		(fp_line
			(start -0.7874 0.4064)
			(end 0.7874 0.4064)
			(stroke
				(width 0.1524)
				(type default)
			)
			(layer "B.SilkS")
		)
		(fp_line
			(start -0.7874 -0.4064)
			(end -0.7874 0.4064)
			(stroke
				(width 0.1524)
				(type default)
			)
			(layer "B.SilkS")
		)
		(fp_poly
			(pts
				(xy 0.5334 0.254) (xy 0.635 0.254) (xy 0.635 0.2286) (xy 0.635 -0.254) (xy 0.5334 -0.254) (xy 0.5334 -0.2794)
				(xy -0.5334 -0.2794) (xy -0.5334 -0.254) (xy -0.635 -0.254) (xy -0.635 0.254) (xy -0.5334 0.254)
				(xy -0.5334 0.2794) (xy 0.508 0.2794) (xy 0.5334 0.2794)
			)
			(stroke
				(width 0)
				(type default)
			)
			(fill no)
			(layer "B.CrtYd")
		)
		(pad "1" smd rect
			(at -0.40005 0)
			(size 0.4572 0.508)
			(layers "B.Cu" "B.Mask" "B.Paste")
			(net "P3V3_BUF")
		)
		(pad "2" smd rect
			(at 0.40005 0)
			(size 0.4572 0.508)
			(layers "B.Cu" "B.Mask" "B.Paste")
			(net "GND")
		)
	)
	(footprint ""
		(layer "B.Cu")
		(at 96.75241 -84.351622 90)
		(property "Reference" "R162"
			(at -1.935988 2.417318 270)
			(unlocked yes)
			(layer "B.SilkS")
			(effects
				(font
					(size 0.7874 0.5842)
					(thickness 0.1524)
				)
				(justify left mirror)
			)
		)
		(property "Value" ""
			(at 0 0 90)
			(layer "B.Fab")
			(effects
				(font
					(size 1.27 1.27)
				)
				(justify mirror)
			)
		)
		(duplicate_pad_numbers_are_jumpers no)
		(fp_line
			(start 0.7874 -0.4064)
			(end -0.7874 -0.4064)
			(stroke
				(width 0.1524)
				(type default)
			)
			(layer "B.SilkS")
		)
		(fp_line
			(start -0.7874 -0.4064)
			(end -0.7874 0.4064)
			(stroke
				(width 0.1524)
				(type default)
			)
			(layer "B.SilkS")
		)
		(fp_line
			(start 0.7874 0.4064)
			(end 0.7874 -0.4064)
			(stroke
				(width 0.1524)
				(type default)
			)
			(layer "B.SilkS")
		)
		(fp_line
			(start -0.7874 0.4064)
			(end 0.7874 0.4064)
			(stroke
				(width 0.1524)
				(type default)
			)
			(layer "B.SilkS")
		)
		(fp_poly
			(pts
				(xy 0.508 0.2794) (xy 0.508 0.2286) (xy 0.635 0.2286) (xy 0.635 -0.254) (xy 0.5334 -0.254) (xy 0.5334 -0.2794)
				(xy -0.5334 -0.2794) (xy -0.5334 -0.254) (xy -0.635 -0.254) (xy -0.635 0.254) (xy -0.5334 0.254)
				(xy -0.5334 0.2794)
			)
			(stroke
				(width 0)
				(type default)
			)
			(fill no)
			(layer "B.CrtYd")
		)
		(pad "1" smd rect
			(at -0.40005 0 270)
			(size 0.4572 0.508)
			(layers "B.Cu" "B.Mask" "B.Paste")
			(net "P3V3_BUF")
		)
		(pad "2" smd rect
			(at 0.40005 0 270)
			(size 0.4572 0.508)
			(layers "B.Cu" "B.Mask" "B.Paste")
			(net "PSU_ALERT_N")
		)
	)
)
